(kicad_pcb
	(version 20260206)
	(generator "pcbnew")
	(generator_version "10.0")
	(general
		(thickness 1.6)
		(legacy_teardrops no)
	)
	(paper "A4")
	(title_block
		(title "Bryce Canyon_R.DPB_16317-1_OCP.brd")
		(comment 1 "Bryce Canyon / footprints 577-580 of 2099")
	)
	(layers
		(0 "F.Cu" signal "TOP")
		(4 "In1.Cu" signal "L2GND")
		(6 "In2.Cu" signal "L3")
		(8 "In3.Cu" signal "L4VCC")
		(10 "In4.Cu" signal "L5VCC")
		(12 "In5.Cu" signal "L6")
		(14 "In6.Cu" signal "L7GND")
		(2 "B.Cu" signal "BOTTOM")
		(9 "F.Adhes" user "F.Adhesive")
		(11 "B.Adhes" user "B.Adhesive")
		(13 "F.Paste" user "Package Geometry/Pastemask Top")
		(15 "B.Paste" user "Package Geometry/Pastemask Bottom")
		(5 "F.SilkS" user "Ref Des/Silkscreen Top")
		(7 "B.SilkS" user "Ref Des/Silkscreen Bottom")
		(1 "F.Mask" user "Board Geometry/Soldermask Top")
		(3 "B.Mask" user "Board Geometry/Soldermask Bottom")
		(17 "Dwgs.User" user "User.Drawings")
		(19 "Cmts.User" user "User.Comments")
		(21 "Eco1.User" user "User.Eco1")
		(23 "Eco2.User" user "User.Eco2")
		(25 "Edge.Cuts" user "Board Geometry/Outline")
		(27 "Margin" user)
		(31 "F.CrtYd" user "Package Geometry/Place Bound Top")
		(29 "B.CrtYd" user "Package Geometry/Place Bound Bottom")
		(35 "F.Fab" user "Ref Des/Assembly Top")
		(33 "B.Fab" user "Ref Des/Assembly Bottom")
	)
	(footprint ""
		(layer "F.Cu")
		(at 438.999884 -379.899926 180)
		(property "Reference" "FAN4"
			(at 0 0 180)
			(layer "F.SilkS")
			(hide yes)
			(effects
				(font
					(size 1.27 1.27)
				)
			)
		)
		(property "Value" "MLX-CONN10D-7-GP"
			(at -15.641574 4.697984 180)
			(unlocked yes)
			(layer "F.Fab")
			(hide yes)
			(effects
				(font
					(size 1.016 1.016)
					(thickness 0.1524)
				)
			)
		)
		(property "Device Type" "15-24-6103"
			(at -15.641574 3.173984 180)
			(unlocked yes)
			(layer "F.Fab")
			(hide yes)
			(effects
				(font
					(size 1.016 1.016)
					(thickness 0.1524)
				)
			)
		)
		(duplicate_pad_numbers_are_jumpers no)
		(fp_line
			(start 14.0462 8.1534)
			(end -14.0462 8.1534)
			(stroke
				(width 0.1524)
				(type default)
			)
			(layer "F.SilkS")
		)
		(fp_line
			(start 14.0462 -6.4516)
			(end 14.0462 8.1534)
			(stroke
				(width 0.1524)
				(type default)
			)
			(layer "F.SilkS")
		)
		(fp_line
			(start 9.9314 -6.4516)
			(end 14.0462 -6.4516)
			(stroke
				(width 0.1524)
				(type default)
			)
			(layer "F.SilkS")
		)
		(fp_line
			(start 9.9314 -14.3256)
			(end 9.9314 -6.4516)
			(stroke
				(width 0.1524)
				(type default)
			)
			(layer "F.SilkS")
		)
		(fp_line
			(start -9.9314 -6.4516)
			(end -9.9314 -14.3256)
			(stroke
				(width 0.1524)
				(type default)
			)
			(layer "F.SilkS")
		)
		(fp_line
			(start -9.9314 -14.3256)
			(end 9.9314 -14.3256)
			(stroke
				(width 0.1524)
				(type default)
			)
			(layer "F.SilkS")
		)
		(fp_line
			(start -14.0462 8.1534)
			(end -14.0462 -6.4516)
			(stroke
				(width 0.1524)
				(type default)
			)
			(layer "F.SilkS")
		)
		(fp_line
			(start -14.0462 -6.4516)
			(end -9.9314 -6.4516)
			(stroke
				(width 0.1524)
				(type default)
			)
			(layer "F.SilkS")
		)
		(fp_circle
			(center 8.400034 -7.29996)
			(end 6.761734 -7.29996)
			(stroke
				(width 0.3048)
				(type default)
			)
			(fill no)
			(layer "F.SilkS")
		)
		(fp_circle
			(center 8.400034 -12.800076)
			(end 6.761734 -12.800076)
			(stroke
				(width 0.3048)
				(type default)
			)
			(fill no)
			(layer "F.SilkS")
		)
		(fp_circle
			(center 4.19989 -7.29996)
			(end 2.56159 -7.29996)
			(stroke
				(width 0.3048)
				(type default)
			)
			(fill no)
			(layer "F.SilkS")
		)
		(fp_circle
			(center 4.19989 -12.800076)
			(end 2.56159 -12.800076)
			(stroke
				(width 0.3048)
				(type default)
			)
			(fill no)
			(layer "F.SilkS")
		)
		(fp_circle
			(center 0 -7.29996)
			(end -1.6383 -7.29996)
			(stroke
				(width 0.3048)
				(type default)
			)
			(fill no)
			(layer "F.SilkS")
		)
		(fp_circle
			(center 0 -12.800076)
			(end -1.6383 -12.800076)
			(stroke
				(width 0.3048)
				(type default)
			)
			(fill no)
			(layer "F.SilkS")
		)
		(fp_circle
			(center -4.19989 -7.29996)
			(end -5.83819 -7.29996)
			(stroke
				(width 0.3048)
				(type default)
			)
			(fill no)
			(layer "F.SilkS")
		)
		(fp_circle
			(center -4.19989 -12.800076)
			(end -5.83819 -12.800076)
			(stroke
				(width 0.3048)
				(type default)
			)
			(fill no)
			(layer "F.SilkS")
		)
		(fp_circle
			(center -8.400034 -7.29996)
			(end -10.038334 -7.29996)
			(stroke
				(width 0.3048)
				(type default)
			)
			(fill no)
			(layer "F.SilkS")
		)
		(fp_circle
			(center -8.400034 -12.800076)
			(end -10.038334 -12.800076)
			(stroke
				(width 0.3048)
				(type default)
			)
			(fill no)
			(layer "F.SilkS")
		)
		(fp_poly
			(pts
				(xy -13.7922 7.8994) (xy -13.7922 -6.1976) (xy -9.2964 -6.1976) (xy -9.2964 -13.6906) (xy 9.2964 -13.6906)
				(xy 9.2964 -6.1976) (xy 13.7922 -6.1976) (xy 13.7922 7.8994)
			)
			(stroke
				(width 0)
				(type default)
			)
			(fill no)
			(layer "F.CrtYd")
		)
		(fp_poly
			(pts
				(xy -14.3002 8.4074) (xy -14.3002 -6.7056) (xy -10.1854 -6.7056) (xy -10.1854 -14.5796) (xy 10.1854 -14.5796)
				(xy 10.1854 -6.7056) (xy 14.3002 -6.7056) (xy 14.3002 -0.00635) (xy 13.7922 -0.00635) (xy 13.7922 -6.1976)
				(xy 9.2964 -6.1976) (xy 9.2964 -13.6906) (xy -9.2964 -13.6906) (xy -9.2964 -6.1976) (xy -13.7922 -6.1976)
				(xy -13.7922 7.8994) (xy 13.7922 7.8994) (xy 13.7922 0.00635) (xy 14.3002 0.00635) (xy 14.3002 8.4074)
			)
			(stroke
				(width 0)
				(type default)
			)
			(fill no)
			(layer "F.CrtYd")
		)
		(fp_poly
			(pts
				(xy -14.3002 8.4074) (xy -14.3002 -6.7056) (xy -10.1854 -6.7056) (xy -10.1854 -14.5796) (xy 10.1854 -14.5796)
				(xy 10.1854 -6.7056) (xy 14.3002 -6.7056) (xy 14.3002 8.4074)
			)
			(stroke
				(width 0)
				(type default)
			)
			(fill no)
			(layer "F.Fab")
		)
		(pad "" np_thru_hole circle
			(at -8.400034 0 180)
			(size 0.254 0.254)
			(drill 3.0226)
			(layers "*.Cu" "*.Mask")
			(clearance 1.7399)
			(thermal_gap 1.7399)
		)
		(pad "" np_thru_hole circle
			(at 8.400034 0 180)
			(size 0.254 0.254)
			(drill 3.0226)
			(layers "*.Cu" "*.Mask")
			(clearance 1.7399)
			(thermal_gap 1.7399)
		)
		(pad "1" thru_hole circle
			(at 8.400034 -7.29996 180)
			(size 2.5654 2.5654)
			(drill 1.8034)
			(layers "*.Cu" "*.Mask")
			(remove_unused_layers no)
			(net "FAN_3_TACH0")
			(clearance 0.127)
			(thermal_gap 0.127)
		)
		(pad "2" thru_hole circle
			(at 8.400034 -12.800076 180)
			(size 2.5654 2.5654)
			(drill 1.8034)
			(layers "*.Cu" "*.Mask")
			(remove_unused_layers no)
			(net "FAN_3_TACH1")
			(clearance 0.127)
			(thermal_gap 0.127)
		)
		(pad "3" thru_hole circle
			(at 4.19989 -7.29996 180)
			(size 2.5654 2.5654)
			(drill 1.8034)
			(layers "*.Cu" "*.Mask")
			(remove_unused_layers no)
			(net "FAN_3_PWM")
			(clearance 0.127)
			(thermal_gap 0.127)
		)
		(pad "4" thru_hole circle
			(at 4.19989 -12.800076 180)
			(size 2.5654 2.5654)
			(drill 1.8034)
			(layers "*.Cu" "*.Mask")
			(remove_unused_layers no)
			(net "FAN_3_PWM")
			(clearance 0.127)
			(thermal_gap 0.127)
		)
		(pad "5" thru_hole circle
			(at 0 -7.29996 180)
			(size 2.5654 2.5654)
			(drill 1.8034)
			(layers "*.Cu" "*.Mask")
			(remove_unused_layers no)
			(net "FAN_3_INS_N")
			(clearance 0.127)
			(thermal_gap 0.127)
		)
		(pad "6" thru_hole circle
			(at 0 -12.800076 180)
			(size 2.5654 2.5654)
			(drill 1.8034)
			(layers "*.Cu" "*.Mask")
			(remove_unused_layers no)
			(net "Net_1769")
			(clearance 0.127)
			(thermal_gap 0.127)
		)
		(pad "7" thru_hole circle
			(at -4.19989 -7.29996 180)
			(size 2.5654 2.5654)
			(drill 1.8034)
			(layers "*.Cu" "*.Mask")
			(remove_unused_layers no)
			(net "P12V_FAN3")
			(clearance 0.127)
			(thermal_gap 0.127)
		)
		(pad "8" thru_hole circle
			(at -4.19989 -12.800076 180)
			(size 2.5654 2.5654)
			(drill 1.8034)
			(layers "*.Cu" "*.Mask")
			(remove_unused_layers no)
			(net "P12V_FAN3")
			(clearance 0.127)
			(thermal_gap 0.127)
		)
		(pad "9" thru_hole circle
			(at -8.400034 -7.29996 180)
			(size 2.5654 2.5654)
			(drill 1.8034)
			(layers "*.Cu" "*.Mask")
			(remove_unused_layers no)
			(net "GND")
			(clearance 0.127)
			(thermal_gap 0.127)
		)
		(pad "10" thru_hole circle
			(at -8.400034 -12.800076 180)
			(size 2.5654 2.5654)
			(drill 1.8034)
			(layers "*.Cu" "*.Mask")
			(remove_unused_layers no)
			(net "GND")
			(clearance 0.127)
			(thermal_gap 0.127)
		)
		(zone
			(layers "F.Cu" "B.Cu" "In1.Cu" "In2.Cu" "In3.Cu" "In4.Cu" "In5.Cu" "In6.Cu")
			(hatch none 0.5)
			(connect_pads
				(clearance 0)
			)
			(min_thickness 0.25)
			(keepout
				(tracks not_allowed)
				(vias allowed)
				(pads allowed)
				(copperpour not_allowed)
				(footprints allowed)
			)
			(placement
				(enabled no)
				(sheetname "")
			)
			(fill
				(thermal_gap 0.5)
				(thermal_bridge_width 0.5)
				(island_removal_mode 0)
			)
			(polygon
				(pts
					(arc
						(start 432.41595 -379.899926)
						(mid 428.78375 -379.899926)
						(end 432.41595 -379.899926)
					)
				)
			)
		)
		(zone
			(layers "F.Cu" "B.Cu" "In1.Cu" "In2.Cu" "In3.Cu" "In4.Cu" "In5.Cu" "In6.Cu")
			(hatch none 0.5)
			(connect_pads
				(clearance 0)
			)
			(min_thickness 0.25)
			(keepout
				(tracks not_allowed)
				(vias allowed)
				(pads allowed)
				(copperpour not_allowed)
				(footprints allowed)
			)
			(placement
				(enabled no)
				(sheetname "")
			)
			(fill
				(thermal_gap 0.5)
				(thermal_bridge_width 0.5)
				(island_removal_mode 0)
			)
			(polygon
				(pts
					(arc
						(start 449.216018 -379.899926)
						(mid 445.583818 -379.899926)
						(end 449.216018 -379.899926)
					)
				)
			)
		)
	)
	(footprint ""
		(layer "F.Cu")
		(at 181.3814 -374.8532 90)
		(property "Reference" "R1002"
			(at 0 0 90)
			(layer "F.SilkS")
			(hide yes)
			(effects
				(font
					(size 1.27 1.27)
				)
			)
		)
		(property "Value" "3K83R2F-GP"
			(at 0.064008 -3.993896 90)
			(unlocked yes)
			(layer "F.Fab")
			(hide yes)
			(effects
				(font
					(size 1.016 1.016)
					(thickness 0.1524)
				)
			)
		)
		(property "Device Type" "R402H16"
			(at 0.064008 -5.517896 90)
			(unlocked yes)
			(layer "F.Fab")
			(hide yes)
			(effects
				(font
					(size 1.016 1.016)
					(thickness 0.1524)
				)
			)
		)
		(duplicate_pad_numbers_are_jumpers no)
		(fp_line
			(start 0.508 -0.9398)
			(end -0.508 -0.9398)
			(stroke
				(width 0.1524)
				(type default)
			)
			(layer "F.SilkS")
		)
		(fp_line
			(start -0.508 -0.9398)
			(end -0.508 0.9398)
			(stroke
				(width 0.1524)
				(type default)
			)
			(layer "F.SilkS")
		)
		(fp_rect
			(start -0.508 0.9398)
			(end 0.508 -0.9398)
			(stroke
				(width 0)
				(type default)
			)
			(fill no)
			(layer "F.CrtYd")
		)
		(fp_rect
			(start -0.508 0.9398)
			(end 0.508 -0.9398)
			(stroke
				(width 0)
				(type default)
			)
			(fill no)
			(layer "F.Fab")
		)
		(pad "1" smd custom
			(at 0 -0.4445 90)
			(size 0.1397 0.1397)
			(layers "F.Cu" "F.Mask" "F.Paste")
			(net "P12V_IN_PGOOD")
			(options
				(clearance outline)
				(anchor circle)
			)
			(primitives
				(gr_poly
					(pts
						(arc
							(start -0.1778 -0.2794)
							(mid -0.249642 -0.249642)
							(end -0.2794 -0.1778)
						)
						(arc
							(start -0.2794 0.1778)
							(mid -0.249642 0.249642)
							(end -0.1778 0.2794)
						)
						(arc
							(start 0.1778 0.2794)
							(mid 0.249642 0.249642)
							(end 0.2794 0.1778)
						)
						(arc
							(start 0.2794 -0.1778)
							(mid 0.249642 -0.249642)
							(end 0.1778 -0.2794)
						)
					)
					(width 0)
					(fill yes)
				)
			)
		)
		(pad "2" smd custom
			(at 0 0.4445 90)
			(size 0.1397 0.1397)
			(layers "F.Cu" "F.Mask" "F.Paste")
			(net "GND")
			(options
				(clearance outline)
				(anchor circle)
			)
			(primitives
				(gr_poly
					(pts
						(arc
							(start -0.1778 -0.2794)
							(mid -0.249642 -0.249642)
							(end -0.2794 -0.1778)
						)
						(arc
							(start -0.2794 0.1778)
							(mid -0.249642 0.249642)
							(end -0.1778 0.2794)
						)
						(arc
							(start 0.1778 0.2794)
							(mid 0.249642 0.249642)
							(end 0.2794 0.1778)
						)
						(arc
							(start 0.2794 -0.1778)
							(mid 0.249642 -0.249642)
							(end 0.1778 -0.2794)
						)
					)
					(width 0)
					(fill yes)
				)
			)
		)
	)
	(footprint ""
		(layer "F.Cu")
		(at 303.604676 -233.195114 90)
		(property "Reference" "R919"
			(at 0 0 90)
			(layer "F.SilkS")
			(hide yes)
			(effects
				(font
					(size 1.27 1.27)
				)
			)
		)
		(property "Value" "0R2J-2-GP"
			(at 0.064008 -3.993896 90)
			(unlocked yes)
			(layer "F.Fab")
			(hide yes)
			(effects
				(font
					(size 1.016 1.016)
					(thickness 0.1524)
				)
			)
		)
		(property "Device Type" "R402H16"
			(at 0.064008 -5.517896 90)
			(unlocked yes)
			(layer "F.Fab")
			(hide yes)
			(effects
				(font
					(size 1.016 1.016)
					(thickness 0.1524)
				)
			)
		)
		(duplicate_pad_numbers_are_jumpers no)
		(fp_line
			(start 0.508 -0.9398)
			(end -0.508 -0.9398)
			(stroke
				(width 0.1524)
				(type default)
			)
			(layer "F.SilkS")
		)
		(fp_line
			(start -0.508 -0.9398)
			(end -0.508 0.9398)
			(stroke
				(width 0.1524)
				(type default)
			)
			(layer "F.SilkS")
		)
		(fp_rect
			(start -0.508 0.9398)
			(end 0.508 -0.9398)
			(stroke
				(width 0)
				(type default)
			)
			(fill no)
			(layer "F.CrtYd")
		)
		(fp_rect
			(start -0.508 0.9398)
			(end 0.508 -0.9398)
			(stroke
				(width 0)
				(type default)
			)
			(fill no)
			(layer "F.Fab")
		)
		(pad "1" smd custom
			(at 0 -0.4445 90)
			(size 0.1397 0.1397)
			(layers "F.Cu" "F.Mask" "F.Paste")
			(net "SCC_B_SLOT_ID_1")
			(options
				(clearance outline)
				(anchor circle)
			)
			(primitives
				(gr_poly
					(pts
						(arc
							(start -0.1778 -0.2794)
							(mid -0.249642 -0.249642)
							(end -0.2794 -0.1778)
						)
						(arc
							(start -0.2794 0.1778)
							(mid -0.249642 0.249642)
							(end -0.1778 0.2794)
						)
						(arc
							(start 0.1778 0.2794)
							(mid 0.249642 0.249642)
							(end 0.2794 0.1778)
						)
						(arc
							(start 0.2794 -0.1778)
							(mid 0.249642 -0.249642)
							(end 0.1778 -0.2794)
						)
					)
					(width 0)
					(fill yes)
				)
			)
		)
		(pad "2" smd custom
			(at 0 0.4445 90)
			(size 0.1397 0.1397)
			(layers "F.Cu" "F.Mask" "F.Paste")
			(net "GND")
			(options
				(clearance outline)
				(anchor circle)
			)
			(primitives
				(gr_poly
					(pts
						(arc
							(start -0.1778 -0.2794)
							(mid -0.249642 -0.249642)
							(end -0.2794 -0.1778)
						)
						(arc
							(start -0.2794 0.1778)
							(mid -0.249642 0.249642)
							(end -0.1778 0.2794)
						)
						(arc
							(start 0.1778 0.2794)
							(mid 0.249642 0.249642)
							(end 0.2794 0.1778)
						)
						(arc
							(start 0.2794 -0.1778)
							(mid 0.249642 -0.249642)
							(end 0.1778 -0.2794)
						)
					)
					(width 0)
					(fill yes)
				)
			)
		)
	)
	(footprint ""
		(layer "F.Cu")
		(at 105.484168 -99.798378 90)
		(property "Reference" "Q258"
			(at 0 0 90)
			(layer "F.SilkS")
			(hide yes)
			(effects
				(font
					(size 1.27 1.27)
				)
			)
		)
		(property "Value" "SSM3K324R-GP"
			(at 0.127 -8.9662 90)
			(unlocked yes)
			(layer "F.Fab")
			(hide yes)
			(effects
				(font
					(size 1.016 1.016)
					(thickness 0.1524)
				)
			)
		)
		(property "Device Type" "SOT23DGS2D4H35"
			(at 0.127 -10.4902 90)
			(unlocked yes)
			(layer "F.Fab")
			(hide yes)
			(effects
				(font
					(size 1.016 1.016)
					(thickness 0.1524)
				)
			)
		)
		(duplicate_pad_numbers_are_jumpers no)
		(fp_line
			(start 1.651 -1.778)
			(end -1.651 -1.778)
			(stroke
				(width 0.1524)
				(type default)
			)
			(layer "F.SilkS")
		)
		(fp_line
			(start -1.651 -1.778)
			(end -1.651 1.778)
			(stroke
				(width 0.1524)
				(type default)
			)
			(layer "F.SilkS")
		)
		(fp_line
			(start 1.651 1.778)
			(end 1.651 -1.778)
			(stroke
				(width 0.1524)
				(type default)
			)
			(layer "F.SilkS")
		)
		(fp_line
			(start -1.651 1.778)
			(end 1.651 1.778)
			(stroke
				(width 0.1524)
				(type default)
			)
			(layer "F.SilkS")
		)
		(fp_poly
			(pts
				(xy -1.778 1.8796) (xy -1.778 -1.8796) (xy 1.778 -1.8796) (xy 1.778 1.8796)
			)
			(stroke
				(width 0)
				(type default)
			)
			(fill no)
			(layer "F.CrtYd")
		)
		(fp_poly
			(pts
				(xy -1.778 1.8796) (xy -1.778 -1.8796) (xy 1.778 -1.8796) (xy 1.778 1.8796)
			)
			(stroke
				(width 0)
				(type default)
			)
			(fill no)
			(layer "F.Fab")
		)
		(pad "D" smd custom
			(at 0 -0.9525 90)
			(size 0.1905 0.1905)
			(layers "F.Cu" "F.Mask" "F.Paste")
			(net "DRV_ACT_15_N")
			(options
				(clearance outline)
				(anchor circle)
			)
			(primitives
				(gr_poly
					(pts
						(arc
							(start -0.1778 0.5715)
							(mid -0.321484 0.511984)
							(end -0.381 0.3683)
						)
						(arc
							(start -0.381 -0.3683)
							(mid -0.321484 -0.511984)
							(end -0.1778 -0.5715)
						)
						(arc
							(start 0.1778 -0.5715)
							(mid 0.321484 -0.511984)
							(end 0.381 -0.3683)
						)
						(arc
							(start 0.381 0.3683)
							(mid 0.321484 0.511984)
							(end 0.1778 0.5715)
						)
					)
					(width 0)
					(fill yes)
				)
			)
		)
		(pad "G" smd custom
			(at -0.98425 0.9525 90)
			(size 0.1905 0.1905)
			(layers "F.Cu" "F.Mask" "F.Paste")
			(net "DRIVE_B_15_ACT")
			(options
				(clearance outline)
				(anchor circle)
			)
			(primitives
				(gr_poly
					(pts
						(arc
							(start -0.1778 0.5715)
							(mid -0.321484 0.511984)
							(end -0.381 0.3683)
						)
						(arc
							(start -0.381 -0.3683)
							(mid -0.321484 -0.511984)
							(end -0.1778 -0.5715)
						)
						(arc
							(start 0.1778 -0.5715)
							(mid 0.321484 -0.511984)
							(end 0.381 -0.3683)
						)
						(arc
							(start 0.381 0.3683)
							(mid 0.321484 0.511984)
							(end 0.1778 0.5715)
						)
					)
					(width 0)
					(fill yes)
				)
			)
		)
		(pad "S" smd custom
			(at 0.98425 0.9525 90)
			(size 0.1905 0.1905)
			(layers "F.Cu" "F.Mask" "F.Paste")
			(net "GND")
			(options
				(clearance outline)
				(anchor circle)
			)
			(primitives
				(gr_poly
					(pts
						(arc
							(start -0.1778 0.5715)
							(mid -0.321484 0.511984)
							(end -0.381 0.3683)
						)
						(arc
							(start -0.381 -0.3683)
							(mid -0.321484 -0.511984)
							(end -0.1778 -0.5715)
						)
						(arc
							(start 0.1778 -0.5715)
							(mid 0.321484 -0.511984)
							(end 0.381 -0.3683)
						)
						(arc
							(start 0.381 0.3683)
							(mid 0.321484 0.511984)
							(end 0.1778 0.5715)
						)
					)
					(width 0)
					(fill yes)
				)
			)
		)
	)
)
